# BARRELEYE_G2-BPX24-EVT-HW-EBOM-X00_20161124-add_2nd_source_X09-20161207-Final.xls — Single-Sole Source Parts List (bom)
| FOXCONN TECHNOLOGY GROUP |  |  |  |  |  |  |  |  |  |  |  |  |  |  |  |  |  |
| BILL OF MATERIAL |  |  |  |  |  |  |  |  |  |  |  |  |  |  |  |  |  |
| REV OF  BOM |  | CUSTOMER | RACKSPACE |  | CUSTOMER P/N |  | PWA P/N： | PWA DESCRIPTION |  |  | PRODUCT CODE |  |  | PWA REV |  | DATE |  |
| Sourcing (Single or Sole | Critical Commodity (Y or N) | Component Class (1, 2, Other) | Customer PSL (Y/N) | Item Number | Foxconn P/N | Customer P/N | Part Description | Mfr. 1 | Mfr Part # 1 | Proposed Mfr. 2 | Proposed Mfr. 2 PN | Qty | RoHS Status | Location | 2nd Source Qual Build: | Customer Comments | ODM Comments |
